(kicad_pcb
	(version 20260206)
	(generator "pcbnew")
	(generator_version "10.0")
	(general
		(thickness 1.6)
		(legacy_teardrops no)
	)
	(paper "A4")
	(title_block
		(title "01162023_DA0F0TEBIF0_F0T_Expander_BD_F_brd_V02_OCP.brd")
		(comment 1 "Grand Teton / footprints 8416-8424 of 9728")
	)
	(layers
		(0 "F.Cu" signal "TOP")
		(4 "In1.Cu" signal "GND")
		(6 "In2.Cu" signal "VCC")
		(8 "In3.Cu" signal "VCC1")
		(10 "In4.Cu" signal "GND1")
		(12 "In5.Cu" signal "IN1")
		(14 "In6.Cu" signal "GND2")
		(16 "In7.Cu" signal "IN2")
		(18 "In8.Cu" signal "GND3")
		(20 "In9.Cu" signal "IN3")
		(22 "In10.Cu" signal "GND4")
		(24 "In11.Cu" signal "IN4")
		(26 "In12.Cu" signal "GND5")
		(28 "In13.Cu" signal "IN5")
		(30 "In14.Cu" signal "GND6")
		(32 "In15.Cu" signal "IN6")
		(34 "In16.Cu" signal "GND7")
		(2 "B.Cu" signal "BOTTOM")
		(9 "F.Adhes" user "F.Adhesive")
		(11 "B.Adhes" user "B.Adhesive")
		(13 "F.Paste" user "Package Geometry/Pastemask Top")
		(15 "B.Paste" user "Package Geometry/Pastemask Bottom")
		(5 "F.SilkS" user "Ref Des/Silkscreen Top")
		(7 "B.SilkS" user "Ref Des/Silkscreen Bottom")
		(1 "F.Mask" user "Board Geometry/Soldermask Top")
		(3 "B.Mask" user "Board Geometry/Soldermask Bottom")
		(17 "Dwgs.User" user "User.Drawings")
		(19 "Cmts.User" user "User.Comments")
		(21 "Eco1.User" user "User.Eco1")
		(23 "Eco2.User" user "User.Eco2")
		(25 "Edge.Cuts" user "Board Geometry/Outline")
		(27 "Margin" user)
		(31 "F.CrtYd" user "Package Geometry/Place Bound Top")
		(29 "B.CrtYd" user "Package Geometry/Place Bound Bottom")
		(35 "F.Fab" user "Ref Des/Assembly Top")
		(33 "B.Fab" user "Ref Des/Assembly Bottom")
	)
	(footprint ""
		(layer "B.Cu")
		(at 52.47005 -305.399948 -90)
		(property "Reference" "C2982"
			(at 0 0 90)
			(layer "B.SilkS")
			(hide yes)
			(effects
				(font
					(size 1.27 1.27)
				)
				(justify mirror)
			)
		)
		(property "Value" ""
			(at 0 0 90)
			(layer "B.Fab")
			(effects
				(font
					(size 1.27 1.27)
				)
				(justify mirror)
			)
		)
		(duplicate_pad_numbers_are_jumpers no)
		(fp_line
			(start -0.299974 0.150114)
			(end 0.299974 0.150114)
			(stroke
				(width 0.1)
				(type default)
			)
			(layer "B.Fab")
		)
		(fp_line
			(start 0.299974 0.150114)
			(end 0.299974 -0.150114)
			(stroke
				(width 0.1)
				(type default)
			)
			(layer "B.Fab")
		)
		(fp_line
			(start -0.299974 -0.150114)
			(end -0.299974 0.150114)
			(stroke
				(width 0.1)
				(type default)
			)
			(layer "B.Fab")
		)
		(fp_line
			(start 0.299974 -0.150114)
			(end -0.299974 -0.150114)
			(stroke
				(width 0.1)
				(type default)
			)
			(layer "B.Fab")
		)
		(pad "1" smd rect
			(at 0.2667 0 90)
			(size 0.3048 0.381)
			(layers "B.Cu" "B.Mask" "B.Paste")
			(net "P1V25_SERDES_VDDPLL_PEX0")
		)
		(pad "2" smd rect
			(at -0.2667 0 90)
			(size 0.3048 0.381)
			(layers "B.Cu" "B.Mask" "B.Paste")
			(net "GND")
		)
	)
	(footprint ""
		(layer "B.Cu")
		(at 333.492348 -308.524402 90)
		(property "Reference" "C4306"
			(at 0 0 90)
			(layer "B.SilkS")
			(hide yes)
			(effects
				(font
					(size 1.27 1.27)
				)
				(justify mirror)
			)
		)
		(property "Value" ""
			(at 0 0 90)
			(layer "B.Fab")
			(effects
				(font
					(size 1.27 1.27)
				)
				(justify mirror)
			)
		)
		(duplicate_pad_numbers_are_jumpers no)
		(fp_line
			(start 0.299974 -0.150114)
			(end -0.299974 -0.150114)
			(stroke
				(width 0.1)
				(type default)
			)
			(layer "B.Fab")
		)
		(fp_line
			(start -0.299974 -0.150114)
			(end -0.299974 0.150114)
			(stroke
				(width 0.1)
				(type default)
			)
			(layer "B.Fab")
		)
		(fp_line
			(start 0.299974 0.150114)
			(end 0.299974 -0.150114)
			(stroke
				(width 0.1)
				(type default)
			)
			(layer "B.Fab")
		)
		(fp_line
			(start -0.299974 0.150114)
			(end 0.299974 0.150114)
			(stroke
				(width 0.1)
				(type default)
			)
			(layer "B.Fab")
		)
		(pad "1" smd rect
			(at 0.2667 0 270)
			(size 0.3048 0.381)
			(layers "B.Cu" "B.Mask" "B.Paste")
			(net "P0V8_PEX2")
		)
		(pad "2" smd rect
			(at -0.2667 0 270)
			(size 0.3048 0.381)
			(layers "B.Cu" "B.Mask" "B.Paste")
			(net "GND")
		)
	)
	(footprint ""
		(layer "B.Cu")
		(at 170.049952 -301.599854 -90)
		(property "Reference" "C1477"
			(at 0 0 90)
			(layer "B.SilkS")
			(hide yes)
			(effects
				(font
					(size 1.27 1.27)
				)
				(justify mirror)
			)
		)
		(property "Value" ""
			(at 0 0 90)
			(layer "B.Fab")
			(effects
				(font
					(size 1.27 1.27)
				)
				(justify mirror)
			)
		)
		(duplicate_pad_numbers_are_jumpers no)
		(fp_line
			(start -0.299974 0.150114)
			(end 0.299974 0.150114)
			(stroke
				(width 0.1)
				(type default)
			)
			(layer "B.Fab")
		)
		(fp_line
			(start 0.299974 0.150114)
			(end 0.299974 -0.150114)
			(stroke
				(width 0.1)
				(type default)
			)
			(layer "B.Fab")
		)
		(fp_line
			(start -0.299974 -0.150114)
			(end -0.299974 0.150114)
			(stroke
				(width 0.1)
				(type default)
			)
			(layer "B.Fab")
		)
		(fp_line
			(start 0.299974 -0.150114)
			(end -0.299974 -0.150114)
			(stroke
				(width 0.1)
				(type default)
			)
			(layer "B.Fab")
		)
		(pad "1" smd rect
			(at 0.2667 0 90)
			(size 0.3048 0.381)
			(layers "B.Cu" "B.Mask" "B.Paste")
			(net "P0V8_SERDES_VDDA_PEX1")
		)
		(pad "2" smd rect
			(at -0.2667 0 90)
			(size 0.3048 0.381)
			(layers "B.Cu" "B.Mask" "B.Paste")
			(net "GND")
		)
	)
	(footprint ""
		(layer "B.Cu")
		(at 112.85728 -313.620404 180)
		(property "Reference" "L48"
			(at 0 0 0)
			(layer "B.SilkS")
			(hide yes)
			(effects
				(font
					(size 1.27 1.27)
				)
				(justify mirror)
			)
		)
		(property "Value" ""
			(at 0 0 0)
			(layer "B.Fab")
			(effects
				(font
					(size 1.27 1.27)
				)
				(justify mirror)
			)
		)
		(duplicate_pad_numbers_are_jumpers no)
		(fp_line
			(start 2.248154 4.9911)
			(end -2.248154 4.9911)
			(stroke
				(width 0.1524)
				(type default)
			)
			(layer "B.SilkS")
		)
		(fp_line
			(start 2.248154 1.88595)
			(end 2.248154 4.9911)
			(stroke
				(width 0.1524)
				(type default)
			)
			(layer "B.SilkS")
		)
		(fp_line
			(start 2.248154 -4.9911)
			(end 2.248154 -1.918462)
			(stroke
				(width 0.1524)
				(type default)
			)
			(layer "B.SilkS")
		)
		(fp_line
			(start -2.248154 4.9911)
			(end -2.248154 1.88595)
			(stroke
				(width 0.1524)
				(type default)
			)
			(layer "B.SilkS")
		)
		(fp_line
			(start -2.248154 -1.918462)
			(end -2.248154 -4.9911)
			(stroke
				(width 0.1524)
				(type default)
			)
			(layer "B.SilkS")
		)
		(fp_line
			(start -2.248154 -4.9911)
			(end 2.248154 -4.9911)
			(stroke
				(width 0.1524)
				(type default)
			)
			(layer "B.SilkS")
		)
		(fp_line
			(start 1.700022 0.899922)
			(end -1.700022 0.899922)
			(stroke
				(width 0.1)
				(type default)
			)
			(layer "B.Fab")
		)
		(fp_line
			(start 1.700022 -0.899922)
			(end 1.700022 0.899922)
			(stroke
				(width 0.1)
				(type default)
			)
			(layer "B.Fab")
		)
		(fp_line
			(start -1.700022 0.899922)
			(end -1.700022 -0.899922)
			(stroke
				(width 0.1)
				(type default)
			)
			(layer "B.Fab")
		)
		(fp_line
			(start -1.700022 -0.899922)
			(end 1.700022 -0.899922)
			(stroke
				(width 0.1)
				(type default)
			)
			(layer "B.Fab")
		)
		(pad "1" smd rect
			(at 1.575054 0)
			(size 1.1684 9.8044)
			(layers "B.Cu" "B.Mask" "B.Paste")
			(net "P0V8_PEX0")
		)
		(pad "2" smd rect
			(at -1.575054 0)
			(size 1.1684 9.8044)
			(layers "B.Cu" "B.Mask" "B.Paste")
			(net "P0V8_SERDES_VDDA_PEX0")
		)
	)
	(footprint ""
		(layer "B.Cu")
		(at 336.618326 -281.024838 90)
		(property "Reference" "PC141"
			(at 0 0 90)
			(layer "B.SilkS")
			(hide yes)
			(effects
				(font
					(size 1.27 1.27)
				)
				(justify mirror)
			)
		)
		(property "Value" ""
			(at 0 0 90)
			(layer "B.Fab")
			(effects
				(font
					(size 1.27 1.27)
				)
				(justify mirror)
			)
		)
		(duplicate_pad_numbers_are_jumpers no)
		(fp_line
			(start 1.524 -0.762)
			(end -1.524 -0.762)
			(stroke
				(width 0.1524)
				(type default)
			)
			(layer "B.SilkS")
		)
		(fp_line
			(start -1.524 -0.762)
			(end -1.524 0.762)
			(stroke
				(width 0.1524)
				(type default)
			)
			(layer "B.SilkS")
		)
		(fp_line
			(start 1.524 0.762)
			(end 1.524 -0.762)
			(stroke
				(width 0.1524)
				(type default)
			)
			(layer "B.SilkS")
		)
		(fp_line
			(start -1.524 0.762)
			(end 1.524 0.762)
			(stroke
				(width 0.1524)
				(type default)
			)
			(layer "B.SilkS")
		)
		(fp_line
			(start 1.1049 -0.724916)
			(end 1.1049 0.724916)
			(stroke
				(width 0.1)
				(type default)
			)
			(layer "B.Fab")
		)
		(fp_line
			(start -1.1049 -0.724916)
			(end 1.1049 -0.724916)
			(stroke
				(width 0.1)
				(type default)
			)
			(layer "B.Fab")
		)
		(fp_line
			(start 1.1049 0.724916)
			(end -1.1049 0.724916)
			(stroke
				(width 0.1)
				(type default)
			)
			(layer "B.Fab")
		)
		(fp_line
			(start -1.1049 0.724916)
			(end -1.1049 -0.724916)
			(stroke
				(width 0.1)
				(type default)
			)
			(layer "B.Fab")
		)
		(pad "1" smd rect
			(at 0.889 0 90)
			(size 1.016 1.27)
			(layers "B.Cu" "B.Mask" "B.Paste")
			(net "SW_P12V_P0V8_PEX2_FLT")
		)
		(pad "2" smd rect
			(at -0.889 0 90)
			(size 1.016 1.27)
			(layers "B.Cu" "B.Mask" "B.Paste")
			(net "GND")
		)
	)
	(footprint ""
		(layer "B.Cu")
		(at 124.236226 -325.186294 -90)
		(property "Reference" "C4257"
			(at 0 0 90)
			(layer "B.SilkS")
			(hide yes)
			(effects
				(font
					(size 1.27 1.27)
				)
				(justify mirror)
			)
		)
		(property "Value" ""
			(at 0 0 90)
			(layer "B.Fab")
			(effects
				(font
					(size 1.27 1.27)
				)
				(justify mirror)
			)
		)
		(duplicate_pad_numbers_are_jumpers no)
		(fp_line
			(start -1.2954 0.5842)
			(end 1.2954 0.5842)
			(stroke
				(width 0.1524)
				(type default)
			)
			(layer "B.SilkS")
		)
		(fp_line
			(start 1.2954 0.5842)
			(end 1.2954 -0.5842)
			(stroke
				(width 0.1524)
				(type default)
			)
			(layer "B.SilkS")
		)
		(fp_line
			(start -1.2954 -0.5842)
			(end -1.2954 0.5842)
			(stroke
				(width 0.1524)
				(type default)
			)
			(layer "B.SilkS")
		)
		(fp_line
			(start 1.2954 -0.5842)
			(end -1.2954 -0.5842)
			(stroke
				(width 0.1524)
				(type default)
			)
			(layer "B.SilkS")
		)
		(fp_line
			(start -0.8636 0.4572)
			(end 0.8636 0.4572)
			(stroke
				(width 0.1)
				(type default)
			)
			(layer "B.Fab")
		)
		(fp_line
			(start 0.8636 0.4572)
			(end 0.8636 0.4064)
			(stroke
				(width 0.1)
				(type default)
			)
			(layer "B.Fab")
		)
		(fp_line
			(start -1.1938 0.4064)
			(end -0.8636 0.4064)
			(stroke
				(width 0.1)
				(type default)
			)
			(layer "B.Fab")
		)
		(fp_line
			(start -0.8636 0.4064)
			(end -0.8636 0.4572)
			(stroke
				(width 0.1)
				(type default)
			)
			(layer "B.Fab")
		)
		(fp_line
			(start 0.8636 0.4064)
			(end 1.1938 0.4064)
			(stroke
				(width 0.1)
				(type default)
			)
			(layer "B.Fab")
		)
		(fp_line
			(start 1.1938 0.4064)
			(end 1.1938 -0.4064)
			(stroke
				(width 0.1)
				(type default)
			)
			(layer "B.Fab")
		)
		(fp_line
			(start -1.1938 -0.4064)
			(end -1.1938 0.4064)
			(stroke
				(width 0.1)
				(type default)
			)
			(layer "B.Fab")
		)
		(fp_line
			(start -0.8636 -0.4064)
			(end -1.1938 -0.4064)
			(stroke
				(width 0.1)
				(type default)
			)
			(layer "B.Fab")
		)
		(fp_line
			(start 0.8636 -0.4064)
			(end 0.8636 -0.4572)
			(stroke
				(width 0.1)
				(type default)
			)
			(layer "B.Fab")
		)
		(fp_line
			(start 1.1938 -0.4064)
			(end 0.8636 -0.4064)
			(stroke
				(width 0.1)
				(type default)
			)
			(layer "B.Fab")
		)
		(fp_line
			(start -0.8636 -0.4572)
			(end -0.8636 -0.4064)
			(stroke
				(width 0.1)
				(type default)
			)
			(layer "B.Fab")
		)
		(fp_line
			(start 0.8636 -0.4572)
			(end -0.8636 -0.4572)
			(stroke
				(width 0.1)
				(type default)
			)
			(layer "B.Fab")
		)
		(pad "1" smd rect
			(at 0.7366 0 180)
			(size 0.7112 0.8128)
			(layers "B.Cu" "B.Mask" "B.Paste")
			(net "P0V8_SERDES_VDDA_PEX1_C3")
		)
		(pad "2" smd rect
			(at -0.7366 0 180)
			(size 0.7112 0.8128)
			(layers "B.Cu" "B.Mask" "B.Paste")
			(net "GND")
		)
	)
	(footprint ""
		(layer "B.Cu")
		(at 385.689602 -234.62996 180)
		(property "Reference" "C2580"
			(at 0 0 0)
			(layer "B.SilkS")
			(hide yes)
			(effects
				(font
					(size 1.27 1.27)
				)
				(justify mirror)
			)
		)
		(property "Value" ""
			(at 0 0 0)
			(layer "B.Fab")
			(effects
				(font
					(size 1.27 1.27)
				)
				(justify mirror)
			)
		)
		(duplicate_pad_numbers_are_jumpers no)
		(fp_line
			(start 0.7874 0.4064)
			(end 0.7874 -0.4064)
			(stroke
				(width 0.1524)
				(type default)
			)
			(layer "B.SilkS")
		)
		(fp_line
			(start 0.7874 -0.4064)
			(end -0.7874 -0.4064)
			(stroke
				(width 0.1524)
				(type default)
			)
			(layer "B.SilkS")
		)
		(fp_line
			(start -0.7874 0.4064)
			(end 0.7874 0.4064)
			(stroke
				(width 0.1524)
				(type default)
			)
			(layer "B.SilkS")
		)
		(fp_line
			(start -0.7874 -0.4064)
			(end -0.7874 0.4064)
			(stroke
				(width 0.1524)
				(type default)
			)
			(layer "B.SilkS")
		)
		(fp_line
			(start 0.67945 0.3048)
			(end 0.67945 -0.305054)
			(stroke
				(width 0.1)
				(type default)
			)
			(layer "B.Fab")
		)
		(fp_line
			(start 0.67945 -0.305054)
			(end 0.12065 -0.305054)
			(stroke
				(width 0.1)
				(type default)
			)
			(layer "B.Fab")
		)
		(fp_line
			(start 0.12065 0.3048)
			(end 0.67945 0.3048)
			(stroke
				(width 0.1)
				(type default)
			)
			(layer "B.Fab")
		)
		(fp_line
			(start 0.12065 0.2794)
			(end 0.12065 0.3048)
			(stroke
				(width 0.1)
				(type default)
			)
			(layer "B.Fab")
		)
		(fp_line
			(start 0.12065 -0.2794)
			(end -0.12065 -0.2794)
			(stroke
				(width 0.1)
				(type default)
			)
			(layer "B.Fab")
		)
		(fp_line
			(start 0.12065 -0.305054)
			(end 0.12065 -0.2794)
			(stroke
				(width 0.1)
				(type default)
			)
			(layer "B.Fab")
		)
		(fp_line
			(start -0.120396 0.3048)
			(end -0.120396 0.2794)
			(stroke
				(width 0.1)
				(type default)
			)
			(layer "B.Fab")
		)
		(fp_line
			(start -0.120396 0.2794)
			(end 0.12065 0.2794)
			(stroke
				(width 0.1)
				(type default)
			)
			(layer "B.Fab")
		)
		(fp_line
			(start -0.12065 -0.2794)
			(end -0.12065 -0.3048)
			(stroke
				(width 0.1)
				(type default)
			)
			(layer "B.Fab")
		)
		(fp_line
			(start -0.12065 -0.3048)
			(end -0.67945 -0.3048)
			(stroke
				(width 0.1)
				(type default)
			)
			(layer "B.Fab")
		)
		(fp_line
			(start -0.67945 0.3048)
			(end -0.120396 0.3048)
			(stroke
				(width 0.1)
				(type default)
			)
			(layer "B.Fab")
		)
		(fp_line
			(start -0.67945 -0.3048)
			(end -0.67945 0.3048)
			(stroke
				(width 0.1)
				(type default)
			)
			(layer "B.Fab")
		)
		(pad "1" smd circle
			(at 0.40005 0)
			(size 0 0)
			(layers "B.Cu" "B.Mask" "B.Paste")
			(net "P3V3_SDB_VPLL")
		)
		(pad "2" smd circle
			(at -0.40005 0)
			(size 0 0)
			(layers "B.Cu" "B.Mask" "B.Paste")
			(net "GND")
		)
	)
	(footprint ""
		(layer "B.Cu")
		(at 113.514124 -331.60843 180)
		(property "Reference" "R1218"
			(at 0 0 0)
			(layer "B.SilkS")
			(hide yes)
			(effects
				(font
					(size 1.27 1.27)
				)
				(justify mirror)
			)
		)
		(property "Value" ""
			(at 0 0 0)
			(layer "B.Fab")
			(effects
				(font
					(size 1.27 1.27)
				)
				(justify mirror)
			)
		)
		(duplicate_pad_numbers_are_jumpers no)
		(fp_line
			(start 0.7874 0.4064)
			(end 0.7874 -0.4064)
			(stroke
				(width 0.1524)
				(type default)
			)
			(layer "B.SilkS")
		)
		(fp_line
			(start 0.7874 -0.4064)
			(end -0.7874 -0.4064)
			(stroke
				(width 0.1524)
				(type default)
			)
			(layer "B.SilkS")
		)
		(fp_line
			(start -0.7874 0.4064)
			(end 0.7874 0.4064)
			(stroke
				(width 0.1524)
				(type default)
			)
			(layer "B.SilkS")
		)
		(fp_line
			(start -0.7874 -0.4064)
			(end -0.7874 0.4064)
			(stroke
				(width 0.1524)
				(type default)
			)
			(layer "B.SilkS")
		)
		(fp_line
			(start 0.67945 0.3048)
			(end 0.67945 -0.305054)
			(stroke
				(width 0.1)
				(type default)
			)
			(layer "B.Fab")
		)
		(fp_line
			(start 0.67945 -0.305054)
			(end 0.12065 -0.305054)
			(stroke
				(width 0.1)
				(type default)
			)
			(layer "B.Fab")
		)
		(fp_line
			(start 0.12065 0.3048)
			(end 0.67945 0.3048)
			(stroke
				(width 0.1)
				(type default)
			)
			(layer "B.Fab")
		)
		(fp_line
			(start 0.12065 0.2794)
			(end 0.12065 0.3048)
			(stroke
				(width 0.1)
				(type default)
			)
			(layer "B.Fab")
		)
		(fp_line
			(start 0.12065 -0.2794)
			(end -0.12065 -0.2794)
			(stroke
				(width 0.1)
				(type default)
			)
			(layer "B.Fab")
		)
		(fp_line
			(start 0.12065 -0.305054)
			(end 0.12065 -0.2794)
			(stroke
				(width 0.1)
				(type default)
			)
			(layer "B.Fab")
		)
		(fp_line
			(start -0.120396 0.3048)
			(end -0.120396 0.2794)
			(stroke
				(width 0.1)
				(type default)
			)
			(layer "B.Fab")
		)
		(fp_line
			(start -0.120396 0.2794)
			(end 0.12065 0.2794)
			(stroke
				(width 0.1)
				(type default)
			)
			(layer "B.Fab")
		)
		(fp_line
			(start -0.12065 -0.2794)
			(end -0.12065 -0.3048)
			(stroke
				(width 0.1)
				(type default)
			)
			(layer "B.Fab")
		)
		(fp_line
			(start -0.12065 -0.3048)
			(end -0.67945 -0.3048)
			(stroke
				(width 0.1)
				(type default)
			)
			(layer "B.Fab")
		)
		(fp_line
			(start -0.67945 0.3048)
			(end -0.120396 0.3048)
			(stroke
				(width 0.1)
				(type default)
			)
			(layer "B.Fab")
		)
		(fp_line
			(start -0.67945 -0.3048)
			(end -0.67945 0.3048)
			(stroke
				(width 0.1)
				(type default)
			)
			(layer "B.Fab")
		)
		(pad "1" smd circle
			(at 0.40005 0)
			(size 0 0)
			(layers "B.Cu" "B.Mask" "B.Paste")
			(net "CLK_100M_MB_0_R_DP")
		)
		(pad "2" smd circle
			(at -0.40005 0)
			(size 0 0)
			(layers "B.Cu" "B.Mask" "B.Paste")
			(net "CLK_100M_MB_0_DP")
		)
	)
	(footprint ""
		(layer "B.Cu")
		(at 54.424834 -297.79976 -90)
		(property "Reference" "C1148"
			(at 0 0 90)
			(layer "B.SilkS")
			(hide yes)
			(effects
				(font
					(size 1.27 1.27)
				)
				(justify mirror)
			)
		)
		(property "Value" ""
			(at 0 0 90)
			(layer "B.Fab")
			(effects
				(font
					(size 1.27 1.27)
				)
				(justify mirror)
			)
		)
		(duplicate_pad_numbers_are_jumpers no)
		(fp_line
			(start -0.299974 0.150114)
			(end 0.299974 0.150114)
			(stroke
				(width 0.1)
				(type default)
			)
			(layer "B.Fab")
		)
		(fp_line
			(start 0.299974 0.150114)
			(end 0.299974 -0.150114)
			(stroke
				(width 0.1)
				(type default)
			)
			(layer "B.Fab")
		)
		(fp_line
			(start -0.299974 -0.150114)
			(end -0.299974 0.150114)
			(stroke
				(width 0.1)
				(type default)
			)
			(layer "B.Fab")
		)
		(fp_line
			(start 0.299974 -0.150114)
			(end -0.299974 -0.150114)
			(stroke
				(width 0.1)
				(type default)
			)
			(layer "B.Fab")
		)
		(pad "1" smd rect
			(at 0.2667 0 90)
			(size 0.3048 0.381)
			(layers "B.Cu" "B.Mask" "B.Paste")
			(net "P0V8_PEX0")
		)
		(pad "2" smd rect
			(at -0.2667 0 90)
			(size 0.3048 0.381)
			(layers "B.Cu" "B.Mask" "B.Paste")
			(net "GND")
		)
	)
)
